(kicad_pcb
	(version 20221018)
	(generator pcbnew)
	(general
    (thickness 1.7403)
  )
	(paper "A4")
	(title_block
    (title "Data Center RDIMM DDR4 Tester")
    (date "2024-09-30")
    (rev "1.2.4")
		(comment 9 "footprints 645-652 of 690")
	)
	(layers
    (0 "F.Cu" signal)
    (1 "In1.Cu" power)
    (2 "In2.Cu" signal)
    (3 "In3.Cu" power)
    (4 "In4.Cu" power)
    (5 "In5.Cu" signal)
    (6 "In6.Cu" power)
    (7 "In7.Cu" signal)
    (8 "In8.Cu" power)
    (9 "In9.Cu" signal)
    (10 "In10.Cu" power)
    (31 "B.Cu" signal)
    (32 "B.Adhes" user "B.Adhesive")
    (33 "F.Adhes" user "F.Adhesive")
    (34 "B.Paste" user)
    (35 "F.Paste" user)
    (36 "B.SilkS" user "B.Silkscreen")
    (37 "F.SilkS" user "F.Silkscreen")
    (38 "B.Mask" user)
    (39 "F.Mask" user)
    (40 "Dwgs.User" user "User.Drawings")
    (41 "Cmts.User" user "User.Comments")
    (42 "Eco1.User" user "User.Eco1")
    (43 "Eco2.User" user "User.Eco2")
    (44 "Edge.Cuts" user)
    (45 "Margin" user)
    (46 "B.CrtYd" user "B.Courtyard")
    (47 "F.CrtYd" user "F.Courtyard")
    (48 "B.Fab" user)
    (49 "F.Fab" user)
  )
	(footprint "data-center-rdimm-ddr4-tester-footprints:C_0201" (layer "B.Cu")
    (at 180.95 96.7 90)
    (descr "Capacitor SMD 0201")
    (tags "capacitor SMD 0201")
    (property "Author" "Antmicro")
    (property "Dielectric" "")
    (property "License" "Apache-2.0")
    (property "MPN" "CC0201KRX6S5BB104")
    (property "Manufacturer" "Yaego")
    (property "Sheetfile" "fpga-power.kicad_sch")
    (property "Sheetname" "FPGA power")
    (property "Val" "100n")
    (property "Voltage" "")
    (property "ki_description" " ")
    (attr smd)
    (fp_text reference "C82" (at 0.74 -0.46 270) (layer "B.SilkS")
        (effects (font (size 0.7 0.7) (thickness 0.15)) (justify left bottom mirror))
    )
    (fp_text value "C_100n_0201" (at 0 -1.4 270) (layer "B.Fab") hide
        (effects (font (size 0.7 0.7) (thickness 0.15)) (justify left bottom mirror))
    )
    (fp_text user "Author: Antmicro" (at -0.72 -5.4 270) (layer "B.Fab") hide
        (effects (font (size 0.7 0.7) (thickness 0.15)) (justify left bottom mirror))
    )
    (fp_text user "${REFERENCE}" (at -0.72 -3.4 270) (layer "B.Fab") hide
        (effects (font (size 0.7 0.7) (thickness 0.15)) (justify left bottom mirror))
    )
    (fp_text user "License: Apache-2.0" (at -0.72 -4.4 270) (layer "B.Fab") hide
        (effects (font (size 0.7 0.7) (thickness 0.15)) (justify left bottom mirror))
    )
    (fp_rect (start -0.72 0.38) (end 0.72 -0.38)
      (stroke (width 0.05) (type solid)) (fill none) (layer "B.CrtYd"))
    (fp_rect (start 0.3 -0.15) (end -0.301 0.149)
      (stroke (width 0.15) (type solid)) (fill none) (layer "B.Fab"))
    (pad "" smd roundrect (at -0.349 0.002 90) (size 0.318 0.36) (layers "B.Paste") (roundrect_rratio 0.25))
    (pad "" smd roundrect (at 0.341 0.002 90) (size 0.318 0.36) (layers "B.Paste") (roundrect_rratio 0.25))
    (pad "1" smd roundrect (at -0.321 0.002 90) (size 0.46 0.4) (layers "B.Cu" "B.Mask") (roundrect_rratio 0.25)
      (net 143 "3V3_SYS") (pintype "passive"))
    (pad "2" smd roundrect (at 0.32 0.002 90) (size 0.46 0.4) (layers "B.Cu" "B.Mask") (roundrect_rratio 0.25)
      (net 9 "GND") (pintype "passive"))
  )
	(footprint "data-center-rdimm-ddr4-tester-footprints:C_2220_5650Metric" (layer "B.Cu")
    (at 195.05 131.95)
    (descr "Capacitor SMD 2220")
    (tags "capacitor SMD 2220")
    (property "Author" "Antmicro")
    (property "Dielectric" "")
    (property "License" "Apache-2.0")
    (property "MPN" "C5750X7S2A226M280KB")
    (property "Manufacturer" "TDK")
    (property "Sheetfile" "ethernet.kicad_sch")
    (property "Sheetname" "Ethernet")
    (property "Val" "22u/100V")
    (property "Voltage" "")
    (property "ki_description" " ")
    (attr smd)
    (fp_text reference "C223" (at 4.58 -1.26 270) (layer "B.SilkS")
        (effects (font (size 0.7 0.7) (thickness 0.15)) (justify left bottom mirror))
    )
    (fp_text value "C_22u_100V_2220" (at 0 -3.9 180) (layer "B.Fab") hide
        (effects (font (size 0.7 0.7) (thickness 0.15)) (justify left bottom mirror))
    )
    (fp_text user "${REFERENCE}" (at -3.7 -5.9 180) (layer "B.Fab") hide
        (effects (font (size 0.7 0.7) (thickness 0.15)) (justify left bottom mirror))
    )
    (fp_text user "Author: Antmicro" (at -3.7 -7.9 180) (layer "B.Fab") hide
        (effects (font (size 0.7 0.7) (thickness 0.15)) (justify left bottom mirror))
    )
    (fp_text user "License: Apache-2.0" (at -3.7 -6.9 180) (layer "B.Fab") hide
        (effects (font (size 0.7 0.7) (thickness 0.15)) (justify left bottom mirror))
    )
    (fp_line (start -1.415 -2.61) (end 1.415 -2.61)
      (stroke (width 0.15) (type solid)) (layer "B.SilkS"))
    (fp_line (start -1.415 2.61) (end 1.415 2.61)
      (stroke (width 0.15) (type solid)) (layer "B.SilkS"))
    (fp_rect (start -3.7 2.95) (end 3.7 -2.95)
      (stroke (width 0.05) (type solid)) (fill none) (layer "B.CrtYd"))
    (fp_rect (start -2.85 2.5) (end 2.85 -2.5)
      (stroke (width 0.15) (type solid)) (fill none) (layer "B.Fab"))
    (pad "1" smd roundrect (at -2.55 0) (size 1.8 5.4) (layers "B.Cu" "B.Paste" "B.Mask") (roundrect_rratio 0.138889)
      (net 360 "/Ethernet/VDD") (pintype "passive"))
    (pad "2" smd roundrect (at 2.55 0) (size 1.8 5.4) (layers "B.Cu" "B.Paste" "B.Mask") (roundrect_rratio 0.138889)
      (net 604 "GNDD") (pintype "passive"))
  )
	(footprint "data-center-rdimm-ddr4-tester-footprints:R_0402_1005Metric" (layer "B.Cu")
    (at 122.26 89.9175 90)
    (descr "Resistor SMD 0402")
    (tags "resistor SMD 0402")
    (property "Author" "Antmicro")
    (property "License" "Apache-2.0")
    (property "MPN" "CR0402-FX-1002GLF")
    (property "Manufacturer" "Bourns")
    (property "Sheetfile" "supply.kicad_sch")
    (property "Sheetname" "Supply")
    (property "Tolerance" "1%")
    (property "Val" "10k")
    (property "ki_description" "10k resistor in 0402 package with 1% tolerance")
    (attr smd)
    (fp_text reference "R194" (at -1.7825 0.44 270) (layer "B.SilkS")
        (effects (font (size 0.7 0.7) (thickness 0.15)) (justify left bottom mirror))
    )
    (fp_text value "R_10k_0402" (at 0 -1.4 270) (layer "B.Fab") hide
        (effects (font (size 0.7 0.7) (thickness 0.15)) (justify left bottom mirror))
    )
    (fp_text user "License: Apache-2.0" (at -0.95 -5.169 270) (layer "B.Fab") hide
        (effects (font (size 0.7 0.7) (thickness 0.15)) (justify left bottom mirror))
    )
    (fp_text user "Author: Antmicro" (at -0.95 -4.169 270) (layer "B.Fab") hide
        (effects (font (size 0.7 0.7) (thickness 0.15)) (justify left bottom mirror))
    )
    (fp_text user "${REFERENCE}" (at -0.95 -3.168 270) (layer "B.Fab") hide
        (effects (font (size 0.7 0.7) (thickness 0.15)) (justify left bottom mirror))
    )
    (fp_rect (start -0.93 0.47) (end 0.93 -0.47)
      (stroke (width 0.05) (type solid)) (fill none) (layer "B.CrtYd"))
    (fp_rect (start -0.5 0.25) (end 0.5 -0.25)
      (stroke (width 0.15) (type solid)) (fill none) (layer "B.Fab"))
    (pad "1" smd roundrect (at -0.485 0 90) (size 0.59 0.64) (layers "B.Cu" "B.Paste" "B.Mask") (roundrect_rratio 0.25)
      (net 143 "3V3_SYS") (pintype "passive"))
    (pad "2" smd roundrect (at 0.485 0 90) (size 0.59 0.64) (layers "B.Cu" "B.Paste" "B.Mask") (roundrect_rratio 0.25)
      (net 660 "Net-(U19-~{PWRDN})") (pintype "passive"))
  )
	(footprint "data-center-rdimm-ddr4-tester-footprints:SOT-753" (layer "B.Cu")
    (at 128.74 105.19 90)
    (property "Author" "Antmicro")
    (property "License" "Apache-2.0")
    (property "MPN" "SN74AHCT1G125DBVR")
    (property "Manufacturer" "Texas Instruments")
    (property "Sheetfile" "supply.kicad_sch")
    (property "Sheetname" "Supply")
    (attr smd)
    (fp_text reference "U21" (at 1.5 -0.98) (layer "B.SilkS")
        (effects (font (size 0.7 0.7) (thickness 0.15)) (justify left bottom mirror))
    )
    (fp_text value "SN74AHCT1G125_SOT" (at 0 -2.9 270) (layer "B.Fab") hide
        (effects (font (size 0.7 0.7) (thickness 0.15)) (justify left bottom mirror))
    )
    (fp_text user "Author: Antmicro" (at -1.651 -7.225 270) (layer "B.Fab") hide
        (effects (font (size 0.7 0.7) (thickness 0.15)) (justify left bottom mirror))
    )
    (fp_text user "${REFERENCE}" (at -1.651 -6.025 270) (layer "B.Fab") hide
        (effects (font (size 0.7 0.7) (thickness 0.15)) (justify left bottom mirror))
    )
    (fp_text user "License: Apache-2.0" (at -1.651 -8.425 270) (layer "B.Fab") hide
        (effects (font (size 0.7 0.7) (thickness 0.15)) (justify left bottom mirror))
    )
    (fp_line (start -1.651 1) (end -1.651 0.701)
      (stroke (width 0.15) (type solid)) (layer "B.SilkS"))
    (fp_line (start -1.648 -1) (end -1.648 -0.677)
      (stroke (width 0.15) (type solid)) (layer "B.SilkS"))
    (fp_line (start -1.5 -1) (end -1.648 -1)
      (stroke (width 0.15) (type solid)) (layer "B.SilkS"))
    (fp_line (start -1.5 1) (end -1.651 1)
      (stroke (width 0.15) (type solid)) (layer "B.SilkS"))
    (fp_line (start 1.5 -0.998) (end 1.648 -0.998)
      (stroke (width 0.15) (type solid)) (layer "B.SilkS"))
    (fp_line (start 1.5 1) (end 1.648 1)
      (stroke (width 0.15) (type solid)) (layer "B.SilkS"))
    (fp_line (start 1.648 -0.998) (end 1.648 -0.699)
      (stroke (width 0.15) (type solid)) (layer "B.SilkS"))
    (fp_line (start 1.648 1) (end 1.648 0.677)
      (stroke (width 0.15) (type solid)) (layer "B.SilkS"))
    (fp_circle (center -1.5 -1.35) (end -1.46 -1.4)
      (stroke (width 0.15) (type solid)) (fill solid) (layer "B.SilkS"))
    (fp_rect (start -1.7 1.901) (end 1.699 -1.898)
      (stroke (width 0.05) (type solid)) (fill none) (layer "B.CrtYd"))
    (fp_line (start -1.526 -0.623) (end -1.526 0.875)
      (stroke (width 0.15) (type solid)) (layer "B.Fab"))
    (fp_line (start -1.526 -0.623) (end -1.351 -0.873)
      (stroke (width 0.15) (type solid)) (layer "B.Fab"))
    (fp_line (start -1.526 0.875) (end 1.523 0.875)
      (stroke (width 0.15) (type solid)) (layer "B.Fab"))
    (fp_line (start -1.351 -0.873) (end 1.523 -0.873)
      (stroke (width 0.15) (type solid)) (layer "B.Fab"))
    (fp_line (start 1.523 0.875) (end 1.523 -0.873)
      (stroke (width 0.15) (type solid)) (layer "B.Fab"))
    (pad "1" smd roundrect (at -0.951 -1.35 90) (size 0.6 1.05) (layers "B.Cu" "B.Paste" "B.Mask") (roundrect_rratio 0.25)
      (net 798 "/Supply/FPGA_PWR_DIS") (pinfunction "~{OE}") (pintype "input"))
    (pad "2" smd roundrect (at 0 -1.35 90) (size 0.6 1.05) (layers "B.Cu" "B.Paste" "B.Mask") (roundrect_rratio 0.25)
      (net 536 "/Supply/SYS_PWR_GOOD") (pinfunction "A") (pintype "input"))
    (pad "3" smd roundrect (at 0.949 -1.35 90) (size 0.6 1.05) (layers "B.Cu" "B.Paste" "B.Mask") (roundrect_rratio 0.25)
      (net 9 "GND") (pinfunction "GND") (pintype "power_in"))
    (pad "4" smd roundrect (at 0.949 1.351 90) (size 0.6 1.05) (layers "B.Cu" "B.Paste" "B.Mask") (roundrect_rratio 0.25)
      (net 790 "/Supply/PWR_SEQ_EN") (pinfunction "Y") (pintype "output"))
    (pad "5" smd roundrect (at -0.951 1.351 90) (size 0.6 1.05) (layers "B.Cu" "B.Paste" "B.Mask") (roundrect_rratio 0.25)
      (net 307 "5V0_SYS") (pinfunction "V_{CC}") (pintype "power_in"))
  )
	(footprint "data-center-rdimm-ddr4-tester-footprints:C_0201" (layer "B.Cu")
    (at 187.09 96.62 180)
    (descr "Capacitor SMD 0201")
    (tags "capacitor SMD 0201")
    (property "Author" "Antmicro")
    (property "Dielectric" "")
    (property "License" "Apache-2.0")
    (property "MPN" "CC0201KRX6S5BB104")
    (property "Manufacturer" "Yaego")
    (property "Sheetfile" "fpga-power.kicad_sch")
    (property "Sheetname" "FPGA power")
    (property "Val" "100n")
    (property "Voltage" "")
    (property "ki_description" " ")
    (attr smd)
    (fp_text reference "C303" (at -3.45 -0.29) (layer "B.SilkS")
        (effects (font (size 0.7 0.7) (thickness 0.15)) (justify left bottom mirror))
    )
    (fp_text value "C_100n_0201" (at 0 -1.4) (layer "B.Fab") hide
        (effects (font (size 0.7 0.7) (thickness 0.15)) (justify left bottom mirror))
    )
    (fp_text user "License: Apache-2.0" (at -0.72 -4.4) (layer "B.Fab") hide
        (effects (font (size 0.7 0.7) (thickness 0.15)) (justify left bottom mirror))
    )
    (fp_text user "${REFERENCE}" (at -0.72 -3.4) (layer "B.Fab") hide
        (effects (font (size 0.7 0.7) (thickness 0.15)) (justify left bottom mirror))
    )
    (fp_text user "Author: Antmicro" (at -0.72 -5.4) (layer "B.Fab") hide
        (effects (font (size 0.7 0.7) (thickness 0.15)) (justify left bottom mirror))
    )
    (fp_rect (start -0.72 0.38) (end 0.72 -0.38)
      (stroke (width 0.05) (type solid)) (fill none) (layer "B.CrtYd"))
    (fp_rect (start 0.3 -0.15) (end -0.301 0.149)
      (stroke (width 0.15) (type solid)) (fill none) (layer "B.Fab"))
    (pad "" smd roundrect (at -0.349 0.002 180) (size 0.318 0.36) (layers "B.Paste") (roundrect_rratio 0.25))
    (pad "" smd roundrect (at 0.341 0.002 180) (size 0.318 0.36) (layers "B.Paste") (roundrect_rratio 0.25))
    (pad "1" smd roundrect (at -0.321 0.002 180) (size 0.46 0.4) (layers "B.Cu" "B.Mask") (roundrect_rratio 0.25)
      (net 143 "3V3_SYS") (pintype "passive"))
    (pad "2" smd roundrect (at 0.32 0.002 180) (size 0.46 0.4) (layers "B.Cu" "B.Mask") (roundrect_rratio 0.25)
      (net 9 "GND") (pintype "passive"))
  )
	(footprint "data-center-rdimm-ddr4-tester-footprints:R_0402_1005Metric" (layer "B.Cu")
    (at 166.2 102.8 180)
    (descr "Resistor SMD 0402")
    (tags "resistor SMD 0402")
    (property "Author" "Antmicro")
    (property "Current" "1A")
    (property "License" "Apache-2.0")
    (property "MPN" "ERJ2GE0R00X")
    (property "Manufacturer" "Panasonic")
    (property "Sheetfile" "ethernet.kicad_sch")
    (property "Sheetname" "Ethernet")
    (property "Tolerance" "")
    (property "Val" "0R")
    (property "ki_description" "0R resistor in 0402 package with unspecified tolerance")
    (attr smd)
    (fp_text reference "R205" (at -1.91 -2.27) (layer "B.SilkS")
        (effects (font (size 0.7 0.7) (thickness 0.15)) (justify left bottom mirror))
    )
    (fp_text value "R_0R_0402" (at 0 -1.4) (layer "B.Fab") hide
        (effects (font (size 0.7 0.7) (thickness 0.15)) (justify left bottom mirror))
    )
    (fp_text user "${REFERENCE}" (at -0.95 -3.168) (layer "B.Fab") hide
        (effects (font (size 0.7 0.7) (thickness 0.15)) (justify left bottom mirror))
    )
    (fp_text user "Author: Antmicro" (at -0.95 -4.169) (layer "B.Fab") hide
        (effects (font (size 0.7 0.7) (thickness 0.15)) (justify left bottom mirror))
    )
    (fp_text user "License: Apache-2.0" (at -0.95 -5.169) (layer "B.Fab") hide
        (effects (font (size 0.7 0.7) (thickness 0.15)) (justify left bottom mirror))
    )
    (fp_rect (start -0.93 0.47) (end 0.93 -0.47)
      (stroke (width 0.05) (type solid)) (fill none) (layer "B.CrtYd"))
    (fp_rect (start -0.5 0.25) (end 0.5 -0.25)
      (stroke (width 0.15) (type solid)) (fill none) (layer "B.Fab"))
    (pad "1" smd roundrect (at -0.485 0 180) (size 0.59 0.64) (layers "B.Cu" "B.Paste" "B.Mask") (roundrect_rratio 0.25)
      (net 751 "PRSNT_M2C") (pintype "passive"))
    (pad "2" smd roundrect (at 0.485 0 180) (size 0.59 0.64) (layers "B.Cu" "B.Paste" "B.Mask") (roundrect_rratio 0.25)
      (net 662 "Net-(U16-SEL)") (pintype "passive"))
  )
	(footprint "data-center-rdimm-ddr4-tester-footprints:FB_0805_2012Metric" (layer "B.Cu")
    (at 177.65 123.6 -90)
    (property "Author" "Antmicro")
    (property "License" "Apache-2.0")
    (property "MPN" "BLM21PG221SN1D")
    (property "Manufacturer" "Murata")
    (property "Sheetfile" "ethernet.kicad_sch")
    (property "Sheetname" "Ethernet")
    (attr smd)
    (fp_text reference "FB9" (at -0.86 0.95 90) (layer "B.SilkS")
        (effects (font (size 0.7 0.7) (thickness 0.15)) (justify left bottom mirror))
    )
    (fp_text value "FB_220Z_2A_0603" (at 0 -1.8 90) (layer "B.Fab") hide
        (effects (font (size 0.7 0.7) (thickness 0.15)) (justify left bottom mirror))
    )
    (fp_text user "${REFERENCE}" (at -1.9 -3.1 90) (layer "B.Fab") hide
        (effects (font (size 0.7 0.7) (thickness 0.15)) (justify left bottom mirror))
    )
    (fp_text user "License: Apache-2.0" (at -1.9 -5.75 90) (layer "B.Fab") hide
        (effects (font (size 0.7 0.7) (thickness 0.15)) (justify left bottom mirror))
    )
    (fp_text user "Author: Antmicro" (at -1.9 -4.4 90) (layer "B.Fab") hide
        (effects (font (size 0.7 0.7) (thickness 0.15)) (justify left bottom mirror))
    )
    (fp_line (start -0.32 -0.699) (end 0.28 -0.699)
      (stroke (width 0.15) (type solid)) (layer "B.SilkS"))
    (fp_line (start -0.3 0.701) (end 0.298 0.701)
      (stroke (width 0.15) (type solid)) (layer "B.SilkS"))
    (fp_rect (start -1.75 0.85) (end 1.75 -0.85)
      (stroke (width 0.05) (type solid)) (fill none) (layer "B.CrtYd"))
    (fp_line (start -0.951 -0.68) (end 0.949 -0.68)
      (stroke (width 0.15) (type solid)) (layer "B.Fab"))
    (fp_line (start -0.951 0.677) (end -0.951 -0.675)
      (stroke (width 0.15) (type solid)) (layer "B.Fab"))
    (fp_line (start -0.951 0.682) (end 0.949 0.682)
      (stroke (width 0.15) (type solid)) (layer "B.Fab"))
    (fp_line (start 0.949 0.677) (end 0.949 -0.675)
      (stroke (width 0.15) (type solid)) (layer "B.Fab"))
    (pad "1" smd roundrect (at -1.1 0.001 270) (size 1 1.4) (layers "B.Cu" "B.Paste" "B.Mask") (roundrect_rratio 0.15)
      (net 808 "/Ethernet/VDD_RAW") (pintype "passive"))
    (pad "2" smd roundrect (at 1.1 0.001 270) (size 1 1.4) (layers "B.Cu" "B.Paste" "B.Mask") (roundrect_rratio 0.15)
      (net 360 "/Ethernet/VDD") (pintype "passive"))
  )
	(footprint "data-center-rdimm-ddr4-tester-footprints:R_0402_1005Metric" (layer "B.Cu")
    (at 134.98 102.59 -90)
    (descr "Resistor SMD 0402")
    (tags "resistor SMD 0402")
    (property "Author" "Antmicro")
    (property "License" "Apache-2.0")
    (property "MPN" "CR0402-FX-1002GLF")
    (property "Manufacturer" "Bourns")
    (property "Sheetfile" "supply.kicad_sch")
    (property "Sheetname" "Supply")
    (property "Tolerance" "1%")
    (property "Val" "10k")
    (property "ki_description" "10k resistor in 0402 package with 1% tolerance")
    (attr smd)
    (fp_text reference "R217" (at -0.95 0.59 90) (layer "B.SilkS")
        (effects (font (size 0.7 0.7) (thickness 0.15)) (justify left bottom mirror))
    )
    (fp_text value "R_10k_0402" (at 0 -1.4 90) (layer "B.Fab") hide
        (effects (font (size 0.7 0.7) (thickness 0.15)) (justify left bottom mirror))
    )
    (fp_text user "${REFERENCE}" (at -0.95 -3.168 90) (layer "B.Fab") hide
        (effects (font (size 0.7 0.7) (thickness 0.15)) (justify left bottom mirror))
    )
    (fp_text user "Author: Antmicro" (at -0.95 -4.169 90) (layer "B.Fab") hide
        (effects (font (size 0.7 0.7) (thickness 0.15)) (justify left bottom mirror))
    )
    (fp_text user "License: Apache-2.0" (at -0.95 -5.169 90) (layer "B.Fab") hide
        (effects (font (size 0.7 0.7) (thickness 0.15)) (justify left bottom mirror))
    )
    (fp_rect (start -0.93 0.47) (end 0.93 -0.47)
      (stroke (width 0.05) (type solid)) (fill none) (layer "B.CrtYd"))
    (fp_rect (start -0.5 0.25) (end 0.5 -0.25)
      (stroke (width 0.15) (type solid)) (fill none) (layer "B.Fab"))
    (pad "1" smd roundrect (at -0.485 0 270) (size 0.59 0.64) (layers "B.Cu" "B.Paste" "B.Mask") (roundrect_rratio 0.25)
      (net 793 "/Supply/VTT_CNTL") (pintype "passive"))
    (pad "2" smd roundrect (at 0.485 0 270) (size 0.59 0.64) (layers "B.Cu" "B.Paste" "B.Mask") (roundrect_rratio 0.25)
      (net 9 "GND") (pintype "passive"))
  )
)
